# T6G (Grand Teton) — schematic netlist excerpt (pin names and nets, part order shuffled) for the footprints in the layout excerpt that follows; sources: Cadence DE-HDL packaged netlist, KiCad conversion of 04192023_DAF0TMB3IC0_F0TG_MB_C_brd_V02_OCP.brd

C435  Q_CAP  22UF 4V 20% X6S  pkg C0402  page 356 : A = P1V8_CPU1_RT3_1A ; B = GND
R3303  Q_RES  0 5% CHIP  pkg 0402LF  page 143 : A = OCP_SFF_PRSNT_ALL_R_N ; B = OCP_SFF_PRSNT_ALL_R1_N

(kicad_pcb
	(version 20260206)
	(generator "pcbnew")
	(generator_version "10.0")
	(general
		(thickness 1.6)
		(legacy_teardrops no)
	)
	(paper "A4")
	(title_block
		(title "04192023_DAF0TMB3IC0_F0TG_MB_C_brd_V02_OCP.brd")
		(comment 1 "Grand Teton / footprints 1207-1208 of 8354")
	)
	(layers
		(0 "F.Cu" signal "TOP")
		(4 "In1.Cu" signal "GND")
		(6 "In2.Cu" signal "IN1")
		(8 "In3.Cu" signal "GND1")
		(10 "In4.Cu" signal "IN2")
		(12 "In5.Cu" signal "GND2")
		(14 "In6.Cu" signal "IN3")
		(16 "In7.Cu" signal "GND3")
		(18 "In8.Cu" signal "VCC")
		(20 "In9.Cu" signal "VCC1")
		(22 "In10.Cu" signal "GND4")
		(24 "In11.Cu" signal "IN4")
		(26 "In12.Cu" signal "GND5")
		(28 "In13.Cu" signal "IN5")
		(30 "In14.Cu" signal "GND6")
		(32 "In15.Cu" signal "IN6")
		(34 "In16.Cu" signal "GND7")
		(2 "B.Cu" signal "BOTTOM")
		(9 "F.Adhes" user "F.Adhesive")
		(11 "B.Adhes" user "B.Adhesive")
		(13 "F.Paste" user "Package Geometry/Pastemask Top")
		(15 "B.Paste" user "Package Geometry/Pastemask Bottom")
		(5 "F.SilkS" user "Ref Des/Silkscreen Top")
		(7 "B.SilkS" user "Ref Des/Silkscreen Bottom")
		(1 "F.Mask" user "Board Geometry/Soldermask Top")
		(3 "B.Mask" user "Board Geometry/Soldermask Bottom")
		(17 "Dwgs.User" user "User.Drawings")
		(19 "Cmts.User" user "User.Comments")
		(21 "Eco1.User" user "User.Eco1")
		(23 "Eco2.User" user "User.Eco2")
		(25 "Edge.Cuts" user "Board Geometry/Outline")
		(27 "Margin" user)
		(31 "F.CrtYd" user "Package Geometry/Place Bound Top")
		(29 "B.CrtYd" user "Package Geometry/Place Bound Bottom")
		(35 "F.Fab" user "Ref Des/Assembly Top")
		(33 "B.Fab" user "Ref Des/Assembly Bottom")
	)
	(footprint ""
		(layer "F.Cu")
		(at 136.59358 -386.44068 90)
		(property "Reference" "C435"
			(at 0 0 90)
			(layer "F.SilkS")
			(hide yes)
			(effects
				(font
					(size 1.27 1.27)
				)
			)
		)
		(property "Value" ""
			(at 0 0 90)
			(layer "F.Fab")
			(effects
				(font
					(size 1.27 1.27)
				)
			)
		)
		(duplicate_pad_numbers_are_jumpers no)
		(fp_line
			(start 0.7874 -0.4064)
			(end 0.7874 0.4064)
			(stroke
				(width 0.1524)
				(type default)
			)
			(layer "F.SilkS")
		)
		(fp_line
			(start -0.7874 -0.4064)
			(end 0.7874 -0.4064)
			(stroke
				(width 0.1524)
				(type default)
			)
			(layer "F.SilkS")
		)
		(fp_line
			(start 0.7874 0.4064)
			(end -0.7874 0.4064)
			(stroke
				(width 0.1524)
				(type default)
			)
			(layer "F.SilkS")
		)
		(fp_line
			(start -0.7874 0.4064)
			(end -0.7874 -0.4064)
			(stroke
				(width 0.1524)
				(type default)
			)
			(layer "F.SilkS")
		)
		(fp_line
			(start -0.12065 -0.305054)
			(end -0.12065 -0.2794)
			(stroke
				(width 0.1)
				(type default)
			)
			(layer "F.Fab")
		)
		(fp_line
			(start -0.67945 -0.305054)
			(end -0.12065 -0.305054)
			(stroke
				(width 0.1)
				(type default)
			)
			(layer "F.Fab")
		)
		(fp_line
			(start 0.67945 -0.3048)
			(end 0.67945 0.3048)
			(stroke
				(width 0.1)
				(type default)
			)
			(layer "F.Fab")
		)
		(fp_line
			(start 0.12065 -0.3048)
			(end 0.67945 -0.3048)
			(stroke
				(width 0.1)
				(type default)
			)
			(layer "F.Fab")
		)
		(fp_line
			(start 0.12065 -0.2794)
			(end 0.12065 -0.3048)
			(stroke
				(width 0.1)
				(type default)
			)
			(layer "F.Fab")
		)
		(fp_line
			(start -0.12065 -0.2794)
			(end 0.12065 -0.2794)
			(stroke
				(width 0.1)
				(type default)
			)
			(layer "F.Fab")
		)
		(fp_line
			(start 0.120396 0.2794)
			(end -0.12065 0.2794)
			(stroke
				(width 0.1)
				(type default)
			)
			(layer "F.Fab")
		)
		(fp_line
			(start -0.12065 0.2794)
			(end -0.12065 0.3048)
			(stroke
				(width 0.1)
				(type default)
			)
			(layer "F.Fab")
		)
		(fp_line
			(start 0.67945 0.3048)
			(end 0.120396 0.3048)
			(stroke
				(width 0.1)
				(type default)
			)
			(layer "F.Fab")
		)
		(fp_line
			(start 0.120396 0.3048)
			(end 0.120396 0.2794)
			(stroke
				(width 0.1)
				(type default)
			)
			(layer "F.Fab")
		)
		(fp_line
			(start -0.12065 0.3048)
			(end -0.67945 0.3048)
			(stroke
				(width 0.1)
				(type default)
			)
			(layer "F.Fab")
		)
		(fp_line
			(start -0.67945 0.3048)
			(end -0.67945 -0.305054)
			(stroke
				(width 0.1)
				(type default)
			)
			(layer "F.Fab")
		)
		(pad "1" smd circle
			(at -0.40005 0 90)
			(size 0 0)
			(layers "F.Cu" "F.Mask" "F.Paste")
			(net "P1V8_CPU1_RT3_1A")
		)
		(pad "2" smd circle
			(at 0.40005 0 90)
			(size 0 0)
			(layers "F.Cu" "F.Mask" "F.Paste")
			(net "GND")
		)
	)
	(footprint ""
		(layer "F.Cu")
		(at 157.88259 -98.755708 90)
		(property "Reference" "R3303"
			(at 0 0 90)
			(layer "F.SilkS")
			(hide yes)
			(effects
				(font
					(size 1.27 1.27)
				)
			)
		)
		(property "Value" ""
			(at 0 0 90)
			(layer "F.Fab")
			(effects
				(font
					(size 1.27 1.27)
				)
			)
		)
		(duplicate_pad_numbers_are_jumpers no)
		(fp_line
			(start 0.7874 -0.4064)
			(end 0.7874 0.4064)
			(stroke
				(width 0.1524)
				(type default)
			)
			(layer "F.SilkS")
		)
		(fp_line
			(start -0.7874 -0.4064)
			(end 0.7874 -0.4064)
			(stroke
				(width 0.1524)
				(type default)
			)
			(layer "F.SilkS")
		)
		(fp_line
			(start 0.7874 0.4064)
			(end -0.7874 0.4064)
			(stroke
				(width 0.1524)
				(type default)
			)
			(layer "F.SilkS")
		)
		(fp_line
			(start -0.7874 0.4064)
			(end -0.7874 -0.4064)
			(stroke
				(width 0.1524)
				(type default)
			)
			(layer "F.SilkS")
		)
		(fp_line
			(start -0.12065 -0.305054)
			(end -0.12065 -0.2794)
			(stroke
				(width 0.1)
				(type default)
			)
			(layer "F.Fab")
		)
		(fp_line
			(start -0.67945 -0.305054)
			(end -0.12065 -0.305054)
			(stroke
				(width 0.1)
				(type default)
			)
			(layer "F.Fab")
		)
		(fp_line
			(start 0.67945 -0.3048)
			(end 0.67945 0.3048)
			(stroke
				(width 0.1)
				(type default)
			)
			(layer "F.Fab")
		)
		(fp_line
			(start 0.12065 -0.3048)
			(end 0.67945 -0.3048)
			(stroke
				(width 0.1)
				(type default)
			)
			(layer "F.Fab")
		)
		(fp_line
			(start 0.12065 -0.2794)
			(end 0.12065 -0.3048)
			(stroke
				(width 0.1)
				(type default)
			)
			(layer "F.Fab")
		)
		(fp_line
			(start -0.12065 -0.2794)
			(end 0.12065 -0.2794)
			(stroke
				(width 0.1)
				(type default)
			)
			(layer "F.Fab")
		)
		(fp_line
			(start 0.120396 0.2794)
			(end -0.12065 0.2794)
			(stroke
				(width 0.1)
				(type default)
			)
			(layer "F.Fab")
		)
		(fp_line
			(start -0.12065 0.2794)
			(end -0.12065 0.3048)
			(stroke
				(width 0.1)
				(type default)
			)
			(layer "F.Fab")
		)
		(fp_line
			(start 0.67945 0.3048)
			(end 0.120396 0.3048)
			(stroke
				(width 0.1)
				(type default)
			)
			(layer "F.Fab")
		)
		(fp_line
			(start 0.120396 0.3048)
			(end 0.120396 0.2794)
			(stroke
				(width 0.1)
				(type default)
			)
			(layer "F.Fab")
		)
		(fp_line
			(start -0.12065 0.3048)
			(end -0.67945 0.3048)
			(stroke
				(width 0.1)
				(type default)
			)
			(layer "F.Fab")
		)
		(fp_line
			(start -0.67945 0.3048)
			(end -0.67945 -0.305054)
			(stroke
				(width 0.1)
				(type default)
			)
			(layer "F.Fab")
		)
		(pad "1" smd circle
			(at -0.40005 0 90)
			(size 0 0)
			(layers "F.Cu" "F.Mask" "F.Paste")
			(net "OCP_SFF_PRSNT_ALL_R_N")
		)
		(pad "2" smd circle
			(at 0.40005 0 90)
			(size 0 0)
			(layers "F.Cu" "F.Mask" "F.Paste")
			(net "OCP_SFF_PRSNT_ALL_R1_N")
		)
	)
)
